#ISCELL
  logical_power cad_note *
  *
#ISCELL
  mstr_misc dns *
  *
#ISCELL
  pure_quanta quanta_title_block_c *
  *
#ISCELL
  logical_power universal_gnd *
  page194_i1
#ISCELL
  logical_power universal_power *
  page194_i10
#ISCELL
  standard offpage *
  page194_i11
#ISCELL
  standard offpage *
  page194_i12
#CELL
  pure_quanta q_res *
  page194_i13
#ISCELL
  logical_power universal_gnd *
  page194_i14
#CELL
  pure_quanta q_cap *
  page194_i15
#CELL
  pure_quanta q_res *
  page194_i16
#CELL
  pure_quanta q_res *
  page194_i17
#CELL
  pure_quanta q_res *
  page194_i18
#CELL
  pure_quanta q_res *
  page194_i19
#CELL
  pure_quanta q_cap *
  page194_i2
#CELL
  pure_quanta tusb211irwbr *
  page194_i20
#ISCELL
  logical_power universal_power *
  page194_i21
#CELL
  pure_quanta q_res *
  page194_i22
#CELL
  pure_quanta q_res *
  page194_i23
#CELL
  pure_quanta q_res *
  page194_i24
#CELL
  pure_quanta q_res *
  page194_i25
#CELL
  pure_quanta q_res *
  page194_i26
#CELL
  pure_quanta q_res *
  page194_i27
#ISCELL
  standard offpage *
  page194_i28
#ISCELL
  standard offpage *
  page194_i29
#ISCELL
  logical_power universal_gnd *
  page194_i3
#ISCELL
  standard offpage *
  page194_i30
#ISCELL
  standard offpage *
  page194_i31
#ISCELL
  standard offpage *
  page194_i32
#ISCELL
  standard offpage *
  page194_i33
#ISCELL
  standard offpage *
  page194_i34
#ISCELL
  logical_power universal_gnd *
  page194_i35
#ISCELL
  logical_power universal_gnd *
  page194_i36
#CELL
  pure_quanta q_res *
  page194_i37
#CELL
  pure_quanta q_res *
  page194_i38
#ISCELL
  standard offpage *
  page194_i39
#CELL
  pure_quanta q_res *
  page194_i4
#CELL
  pure_quanta gl852gohy60 *
  page194_i40
#CELL
  pure_quanta q_res *
  page194_i41
#ISCELL
  logical_power universal_gnd *
  page194_i42
#CELL
  pure_quanta q_cap *
  page194_i43
#ISCELL
  logical_power universal_power *
  page194_i44
#CELL
  pure_quanta q_cap *
  page194_i45
#CELL
  pure_quanta q_cap *
  page194_i46
#CELL
  pure_quanta q_cap *
  page194_i47
#ISCELL
  logical_power universal_power *
  page194_i48
#CELL
  pure_quanta q_cap *
  page194_i49
#ISCELL
  standard offpage *
  page194_i5
#CELL
  pure_quanta q_res *
  page194_i50
#CELL
  pure_quanta q_cap *
  page194_i51
#CELL
  pure_quanta q_cap *
  page194_i52
#CELL
  pure_quanta q_cap *
  page194_i53
#ISCELL
  logical_power universal_gnd *
  page194_i54
#CELL
  pure_quanta q_cap *
  page194_i55
#CELL
  pure_quanta q_cap *
  page194_i56
#ISCELL
  logical_power universal_gnd *
  page194_i57
#CELL
  pure_quanta q_cap *
  page194_i58
#ISCELL
  logical_power universal_gnd *
  page194_i59
#ISCELL
  standard offpage *
  page194_i6
#CELL
  pure_quanta q_res *
  page194_i60
#CELL
  pure_quanta q_res *
  page194_i61
#ISCELL
  logical_power universal_power *
  page194_i62
#ISCELL
  logical_power universal_gnd *
  page194_i63
#ISCELL
  standard offpage *
  page194_i64
#ISCELL
  standard offpage *
  page194_i65
#ISCELL
  standard offpage *
  page194_i66
#ISCELL
  standard offpage *
  page194_i67
#ISCELL
  logical_power universal_gnd *
  page194_i7
#CELL
  pure_quanta q_res *
  page194_i72
#CELL
  pure_quanta q_res *
  page194_i73
#ISCELL
  standard offpage *
  page194_i74
#CELL
  pure_quanta q_res *
  page194_i75
#ISCELL
  logical_power universal_gnd *
  page194_i76
#CELL
  pure_quanta q_res *
  page194_i77
#CELL
  pure_quanta q_res *
  page194_i78
#ISCELL
  standard offpage *
  page194_i79
#CELL
  pure_quanta q_res *
  page194_i8
#ISCELL
  logical_power universal_gnd *
  page194_i80
#CELL
  pure_quanta q_cap *
  page194_i81
#ISCELL
  logical_power universal_gnd *
  page194_i82
#CELL
  pure_quanta q_xtal_4p_13bi_24gnd *
  page194_i83
#ISCELL
  logical_power universal_gnd *
  page194_i84
#CELL
  pure_quanta q_cap *
  page194_i85
#ISCELL
  logical_power universal_gnd *
  page194_i86
#ISCELL
  standard offpage *
  page194_i87
#CELL
  pure_quanta q_res *
  page194_i88
#ISCELL
  logical_power universal_gnd *
  page194_i89
#CELL
  pure_quanta q_res *
  page194_i9
#CELL
  pure_quanta q_res *
  page194_i90
#ISCELL
  logical_power universal_gnd *
  page194_i91
